# TIMECARD (Time Appliance Project (Time Card)) — schematic netlist excerpt (pin names and nets, part order shuffled) for the footprints in the layout excerpt that follows; sources: Cadence DE-HDL packaged netlist, KiCad conversion of R4006-B0001-02_R01.brd

R138  RESISTOR  330OHM 1%  pkg SMC_0402R_H016  page 26 : \1\ = UNNAMED_14_OPTICAL_I140_A ; \2\ = XP3R3V_FPGA
R280  RESISTOR  330OHM 1%  pkg SMC_0402R_H016  page 26 : \1\ = UNNAMED_14_OPTICAL_I139_A ; \2\ = XP3R3V_FPGA

(kicad_pcb
	(version 20260206)
	(generator "pcbnew")
	(generator_version "10.0")
	(general
		(thickness 1.6)
		(legacy_teardrops no)
	)
	(paper "A4")
	(title_block
		(title "timecard-production-celestica-r4006 — R4006-B0001-02_R01.brd")
		(comment 1 "Time Appliance Project (Time Card) / footprints 691-692 of 1113")
	)
	(layers
		(0 "F.Cu" signal "TOP")
		(4 "In1.Cu" signal "L02_GND1")
		(6 "In2.Cu" signal "L03_SIG1")
		(8 "In3.Cu" signal "L04_GND2")
		(10 "In4.Cu" signal "L05_VCC1")
		(12 "In5.Cu" signal "L06_VCC2")
		(14 "In6.Cu" signal "L07_GND3")
		(16 "In7.Cu" signal "L08_SIG2")
		(18 "In8.Cu" signal "L09_GND4")
		(2 "B.Cu" signal "BOTTOM")
		(9 "F.Adhes" user "F.Adhesive")
		(11 "B.Adhes" user "B.Adhesive")
		(13 "F.Paste" user "Package Geometry/Pastemask Top")
		(15 "B.Paste" user "Package Geometry/Pastemask Bottom")
		(5 "F.SilkS" user "Ref Des/Silkscreen Top")
		(7 "B.SilkS" user "Ref Des/Silkscreen Bottom")
		(1 "F.Mask" user "Board Geometry/Soldermask Top")
		(3 "B.Mask" user "Board Geometry/Soldermask Bottom")
		(17 "Dwgs.User" user "User.Drawings")
		(19 "Cmts.User" user "User.Comments")
		(21 "Eco1.User" user "User.Eco1")
		(23 "Eco2.User" user "User.Eco2")
		(25 "Edge.Cuts" user "Board Geometry/Outline")
		(27 "Margin" user)
		(31 "F.CrtYd" user "Package Geometry/Place Bound Top")
		(29 "B.CrtYd" user "Package Geometry/Place Bound Bottom")
		(35 "F.Fab" user "Ref Des/Assembly Top")
		(33 "B.Fab" user "Ref Des/Assembly Bottom")
	)
	(footprint ""
		(layer "B.Cu")
		(at 155.956 -107.696 90)
		(property "Reference" "R280"
			(at 0.381 1.23063 270)
			(unlocked yes)
			(layer "B.SilkS")
			(effects
				(font
					(size 0.7874 0.5842)
					(thickness 0.1524)
				)
				(justify mirror)
			)
		)
		(property "Value" "VAL*"
			(at -0.02032 2.13233 90)
			(unlocked yes)
			(layer "B.Fab")
			(hide yes)
			(effects
				(font
					(size 0.7874 0.5842)
					(thickness 0.1524)
				)
				(justify mirror)
			)
		)
		(property "Tolerance" "TOL*"
			(at -0.044704 3.05435 90)
			(unlocked yes)
			(layer "Cmts.User")
			(hide yes)
			(effects
				(font
					(size 0.7874 0.5842)
					(thickness 0.1524)
				)
				(justify mirror)
			)
		)
		(property "User Part Number" "PARTNUM*"
			(at -0.02032 4.024884 90)
			(unlocked yes)
			(layer "Cmts.User")
			(hide yes)
			(effects
				(font
					(size 0.7874 0.5842)
					(thickness 0.1524)
				)
				(justify mirror)
			)
		)
		(property "Device Type" "RESISTOR-G155-13300-01,330OHM,A"
			(at -0.008382 1.210564 90)
			(unlocked yes)
			(layer "B.Fab")
			(hide yes)
			(effects
				(font
					(size 0.7874 0.5842)
					(thickness 0.1524)
				)
				(justify mirror)
			)
		)
		(duplicate_pad_numbers_are_jumpers no)
		(fp_line
			(start 1.143 -0.5588)
			(end 1.143 0.5588)
			(stroke
				(width 0.1)
				(type default)
			)
			(layer "B.SilkS")
		)
		(fp_line
			(start -1.143 -0.5588)
			(end 1.143 -0.5588)
			(stroke
				(width 0.1)
				(type default)
			)
			(layer "B.SilkS")
		)
		(fp_line
			(start 1.143 0.5588)
			(end -1.143 0.5588)
			(stroke
				(width 0.1)
				(type default)
			)
			(layer "B.SilkS")
		)
		(fp_line
			(start -1.143 0.5588)
			(end -1.143 -0.5588)
			(stroke
				(width 0.1)
				(type default)
			)
			(layer "B.SilkS")
		)
		(fp_rect
			(start -1.143 -0.5588)
			(end 1.143 0.5588)
			(stroke
				(width 0)
				(type default)
			)
			(fill no)
			(layer "B.CrtYd")
		)
		(fp_line
			(start 0.508 -0.3048)
			(end 0.508 0.3048)
			(stroke
				(width 0.1)
				(type default)
			)
			(layer "B.Fab")
		)
		(fp_line
			(start -0.508 -0.3048)
			(end 0.508 -0.3048)
			(stroke
				(width 0.1)
				(type default)
			)
			(layer "B.Fab")
		)
		(fp_line
			(start 0.508 0.3048)
			(end -0.508 0.3048)
			(stroke
				(width 0.1)
				(type default)
			)
			(layer "B.Fab")
		)
		(fp_line
			(start -0.508 0.3048)
			(end -0.508 -0.3048)
			(stroke
				(width 0.1)
				(type default)
			)
			(layer "B.Fab")
		)
		(pad "1" smd rect
			(at 0.5334 0 270)
			(size 0.7112 0.6096)
			(layers "B.Cu" "B.Mask" "B.Paste")
			(net "UNNAMED_14_OPTICAL_I139_A")
		)
		(pad "2" smd rect
			(at -0.5334 0 270)
			(size 0.7112 0.6096)
			(layers "B.Cu" "B.Mask" "B.Paste")
			(net "XP3R3V_FPGA")
		)
		(zone
			(layer "B.Cu")
			(hatch none 0.5)
			(connect_pads
				(clearance 0)
			)
			(min_thickness 0.25)
			(keepout
				(tracks allowed)
				(vias not_allowed)
				(pads allowed)
				(copperpour not_allowed)
				(footprints allowed)
			)
			(placement
				(enabled no)
				(sheetname "")
			)
			(fill
				(thermal_gap 0.5)
				(thermal_bridge_width 0.5)
				(island_removal_mode 0)
			)
			(polygon
				(pts
					(xy 155.6512 -107.6198) (xy 156.2608 -107.6198) (xy 156.2608 -107.7722) (xy 155.6512 -107.7722)
				)
			)
		)
	)
	(footprint ""
		(layer "B.Cu")
		(at 138.049 -105.283 -90)
		(property "Reference" "R138"
			(at 2.45237 0.254 0)
			(unlocked yes)
			(layer "B.SilkS")
			(effects
				(font
					(size 0.7874 0.5842)
					(thickness 0.1524)
				)
				(justify mirror)
			)
		)
		(property "Value" "VAL*"
			(at -0.02032 2.13233 270)
			(unlocked yes)
			(layer "B.Fab")
			(hide yes)
			(effects
				(font
					(size 0.7874 0.5842)
					(thickness 0.1524)
				)
				(justify mirror)
			)
		)
		(property "Tolerance" "TOL*"
			(at -0.044704 3.05435 270)
			(unlocked yes)
			(layer "Cmts.User")
			(hide yes)
			(effects
				(font
					(size 0.7874 0.5842)
					(thickness 0.1524)
				)
				(justify mirror)
			)
		)
		(property "User Part Number" "PARTNUM*"
			(at -0.02032 4.024884 270)
			(unlocked yes)
			(layer "Cmts.User")
			(hide yes)
			(effects
				(font
					(size 0.7874 0.5842)
					(thickness 0.1524)
				)
				(justify mirror)
			)
		)
		(property "Device Type" "RESISTOR-G155-13300-01,330OHM,A"
			(at -0.008382 1.210564 270)
			(unlocked yes)
			(layer "B.Fab")
			(hide yes)
			(effects
				(font
					(size 0.7874 0.5842)
					(thickness 0.1524)
				)
				(justify mirror)
			)
		)
		(duplicate_pad_numbers_are_jumpers no)
		(fp_line
			(start -1.143 0.5588)
			(end -1.143 -0.5588)
			(stroke
				(width 0.1)
				(type default)
			)
			(layer "B.SilkS")
		)
		(fp_line
			(start 1.143 0.5588)
			(end -1.143 0.5588)
			(stroke
				(width 0.1)
				(type default)
			)
			(layer "B.SilkS")
		)
		(fp_line
			(start -1.143 -0.5588)
			(end 1.143 -0.5588)
			(stroke
				(width 0.1)
				(type default)
			)
			(layer "B.SilkS")
		)
		(fp_line
			(start 1.143 -0.5588)
			(end 1.143 0.5588)
			(stroke
				(width 0.1)
				(type default)
			)
			(layer "B.SilkS")
		)
		(fp_rect
			(start -1.143 -0.5588)
			(end 1.143 0.5588)
			(stroke
				(width 0)
				(type default)
			)
			(fill no)
			(layer "B.CrtYd")
		)
		(fp_line
			(start -0.508 0.3048)
			(end -0.508 -0.3048)
			(stroke
				(width 0.1)
				(type default)
			)
			(layer "B.Fab")
		)
		(fp_line
			(start 0.508 0.3048)
			(end -0.508 0.3048)
			(stroke
				(width 0.1)
				(type default)
			)
			(layer "B.Fab")
		)
		(fp_line
			(start -0.508 -0.3048)
			(end 0.508 -0.3048)
			(stroke
				(width 0.1)
				(type default)
			)
			(layer "B.Fab")
		)
		(fp_line
			(start 0.508 -0.3048)
			(end 0.508 0.3048)
			(stroke
				(width 0.1)
				(type default)
			)
			(layer "B.Fab")
		)
		(pad "1" smd rect
			(at 0.5334 0 90)
			(size 0.7112 0.6096)
			(layers "B.Cu" "B.Mask" "B.Paste")
			(net "UNNAMED_14_OPTICAL_I140_A")
		)
		(pad "2" smd rect
			(at -0.5334 0 90)
			(size 0.7112 0.6096)
			(layers "B.Cu" "B.Mask" "B.Paste")
			(net "XP3R3V_FPGA")
		)
		(zone
			(layer "B.Cu")
			(hatch none 0.5)
			(connect_pads
				(clearance 0)
			)
			(min_thickness 0.25)
			(keepout
				(tracks allowed)
				(vias not_allowed)
				(pads allowed)
				(copperpour not_allowed)
				(footprints allowed)
			)
			(placement
				(enabled no)
				(sheetname "")
			)
			(fill
				(thermal_gap 0.5)
				(thermal_bridge_width 0.5)
				(island_removal_mode 0)
			)
			(polygon
				(pts
					(xy 138.3538 -105.3592) (xy 137.7442 -105.3592) (xy 137.7442 -105.2068) (xy 138.3538 -105.2068)
				)
			)
		)
	)
)
